# T6G (Grand Teton) — schematic netlist excerpt (pin names and nets, part order shuffled) for the footprints in the layout excerpt that follows; sources: Cadence DE-HDL packaged netlist, KiCad conversion of 04192023_DAF0TMB3IC0_F0TG_MB_C_brd_V02_OCP.brd

PC189_4  Q_CAP  22UF 4V 20% X6S  pkg C0805  page 206 : A = PVDDIO_P0 ; B = GND
C2351  Q_CAP  22UF 4V 20% X6S  pkg C0402  page 73 : A = PVDDCR_CPU1_P1 ; B = GND
R232  Q_RES  33 5% CHIP  pkg 0402LF  page 82 : A = FM_PVDDCR_CPU1_P0_EN ; B = FM_PVDDCR_CPU1_P0_R_EN

(kicad_pcb
	(version 20260206)
	(generator "pcbnew")
	(generator_version "10.0")
	(general
		(thickness 1.6)
		(legacy_teardrops no)
	)
	(paper "A4")
	(title_block
		(title "04192023_DAF0TMB3IC0_F0TG_MB_C_brd_V02_OCP.brd")
		(comment 1 "Grand Teton / footprints 7334-7336 of 8354")
	)
	(layers
		(0 "F.Cu" signal "TOP")
		(4 "In1.Cu" signal "GND")
		(6 "In2.Cu" signal "IN1")
		(8 "In3.Cu" signal "GND1")
		(10 "In4.Cu" signal "IN2")
		(12 "In5.Cu" signal "GND2")
		(14 "In6.Cu" signal "IN3")
		(16 "In7.Cu" signal "GND3")
		(18 "In8.Cu" signal "VCC")
		(20 "In9.Cu" signal "VCC1")
		(22 "In10.Cu" signal "GND4")
		(24 "In11.Cu" signal "IN4")
		(26 "In12.Cu" signal "GND5")
		(28 "In13.Cu" signal "IN5")
		(30 "In14.Cu" signal "GND6")
		(32 "In15.Cu" signal "IN6")
		(34 "In16.Cu" signal "GND7")
		(2 "B.Cu" signal "BOTTOM")
		(9 "F.Adhes" user "F.Adhesive")
		(11 "B.Adhes" user "B.Adhesive")
		(13 "F.Paste" user "Package Geometry/Pastemask Top")
		(15 "B.Paste" user "Package Geometry/Pastemask Bottom")
		(5 "F.SilkS" user "Ref Des/Silkscreen Top")
		(7 "B.SilkS" user "Ref Des/Silkscreen Bottom")
		(1 "F.Mask" user "Board Geometry/Soldermask Top")
		(3 "B.Mask" user "Board Geometry/Soldermask Bottom")
		(17 "Dwgs.User" user "User.Drawings")
		(19 "Cmts.User" user "User.Comments")
		(21 "Eco1.User" user "User.Eco1")
		(23 "Eco2.User" user "User.Eco2")
		(25 "Edge.Cuts" user "Board Geometry/Outline")
		(27 "Margin" user)
		(31 "F.CrtYd" user "Package Geometry/Place Bound Top")
		(29 "B.CrtYd" user "Package Geometry/Place Bound Bottom")
		(35 "F.Fab" user "Ref Des/Assembly Top")
		(33 "B.Fab" user "Ref Des/Assembly Bottom")
	)
	(footprint ""
		(layer "B.Cu")
		(at 188.849 -100.294948 -90)
		(property "Reference" "R232"
			(at 0 0 90)
			(layer "B.SilkS")
			(hide yes)
			(effects
				(font
					(size 1.27 1.27)
				)
				(justify mirror)
			)
		)
		(property "Value" ""
			(at 0 0 90)
			(layer "B.Fab")
			(effects
				(font
					(size 1.27 1.27)
				)
				(justify mirror)
			)
		)
		(duplicate_pad_numbers_are_jumpers no)
		(fp_line
			(start -0.7874 0.4064)
			(end 0.7874 0.4064)
			(stroke
				(width 0.1524)
				(type default)
			)
			(layer "B.SilkS")
		)
		(fp_line
			(start 0.7874 0.4064)
			(end 0.7874 -0.4064)
			(stroke
				(width 0.1524)
				(type default)
			)
			(layer "B.SilkS")
		)
		(fp_line
			(start -0.7874 -0.4064)
			(end -0.7874 0.4064)
			(stroke
				(width 0.1524)
				(type default)
			)
			(layer "B.SilkS")
		)
		(fp_line
			(start 0.7874 -0.4064)
			(end -0.7874 -0.4064)
			(stroke
				(width 0.1524)
				(type default)
			)
			(layer "B.SilkS")
		)
		(fp_line
			(start -0.67945 0.3048)
			(end -0.120396 0.3048)
			(stroke
				(width 0.1)
				(type default)
			)
			(layer "B.Fab")
		)
		(fp_line
			(start -0.120396 0.3048)
			(end -0.120396 0.2794)
			(stroke
				(width 0.1)
				(type default)
			)
			(layer "B.Fab")
		)
		(fp_line
			(start 0.12065 0.3048)
			(end 0.67945 0.3048)
			(stroke
				(width 0.1)
				(type default)
			)
			(layer "B.Fab")
		)
		(fp_line
			(start 0.67945 0.3048)
			(end 0.67945 -0.305054)
			(stroke
				(width 0.1)
				(type default)
			)
			(layer "B.Fab")
		)
		(fp_line
			(start -0.120396 0.2794)
			(end 0.12065 0.2794)
			(stroke
				(width 0.1)
				(type default)
			)
			(layer "B.Fab")
		)
		(fp_line
			(start 0.12065 0.2794)
			(end 0.12065 0.3048)
			(stroke
				(width 0.1)
				(type default)
			)
			(layer "B.Fab")
		)
		(fp_line
			(start -0.12065 -0.2794)
			(end -0.12065 -0.3048)
			(stroke
				(width 0.1)
				(type default)
			)
			(layer "B.Fab")
		)
		(fp_line
			(start 0.12065 -0.2794)
			(end -0.12065 -0.2794)
			(stroke
				(width 0.1)
				(type default)
			)
			(layer "B.Fab")
		)
		(fp_line
			(start -0.67945 -0.3048)
			(end -0.67945 0.3048)
			(stroke
				(width 0.1)
				(type default)
			)
			(layer "B.Fab")
		)
		(fp_line
			(start -0.12065 -0.3048)
			(end -0.67945 -0.3048)
			(stroke
				(width 0.1)
				(type default)
			)
			(layer "B.Fab")
		)
		(fp_line
			(start 0.12065 -0.305054)
			(end 0.12065 -0.2794)
			(stroke
				(width 0.1)
				(type default)
			)
			(layer "B.Fab")
		)
		(fp_line
			(start 0.67945 -0.305054)
			(end 0.12065 -0.305054)
			(stroke
				(width 0.1)
				(type default)
			)
			(layer "B.Fab")
		)
		(pad "1" smd circle
			(at 0.40005 0 90)
			(size 0 0)
			(layers "B.Cu" "B.Mask" "B.Paste")
			(net "FM_PVDDCR_CPU1_P0_EN")
		)
		(pad "2" smd circle
			(at -0.40005 0 90)
			(size 0 0)
			(layers "B.Cu" "B.Mask" "B.Paste")
			(net "FM_PVDDCR_CPU1_P0_R_EN")
		)
	)
	(footprint ""
		(layer "B.Cu")
		(at 278.713184 -337.984846 -90)
		(property "Reference" "PC189_4"
			(at 0 0 90)
			(layer "B.SilkS")
			(hide yes)
			(effects
				(font
					(size 1.27 1.27)
				)
				(justify mirror)
			)
		)
		(property "Value" ""
			(at 0 0 90)
			(layer "B.Fab")
			(effects
				(font
					(size 1.27 1.27)
				)
				(justify mirror)
			)
		)
		(duplicate_pad_numbers_are_jumpers no)
		(fp_line
			(start -1.524 0.762)
			(end 1.524 0.762)
			(stroke
				(width 0.1524)
				(type default)
			)
			(layer "B.SilkS")
		)
		(fp_line
			(start 1.524 0.762)
			(end 1.524 -0.762)
			(stroke
				(width 0.1524)
				(type default)
			)
			(layer "B.SilkS")
		)
		(fp_line
			(start -1.524 -0.762)
			(end -1.524 0.762)
			(stroke
				(width 0.1524)
				(type default)
			)
			(layer "B.SilkS")
		)
		(fp_line
			(start 1.524 -0.762)
			(end -1.524 -0.762)
			(stroke
				(width 0.1524)
				(type default)
			)
			(layer "B.SilkS")
		)
		(fp_line
			(start -1.1049 0.724916)
			(end -1.1049 -0.724916)
			(stroke
				(width 0.1)
				(type default)
			)
			(layer "B.Fab")
		)
		(fp_line
			(start 1.1049 0.724916)
			(end -1.1049 0.724916)
			(stroke
				(width 0.1)
				(type default)
			)
			(layer "B.Fab")
		)
		(fp_line
			(start -1.1049 -0.724916)
			(end 1.1049 -0.724916)
			(stroke
				(width 0.1)
				(type default)
			)
			(layer "B.Fab")
		)
		(fp_line
			(start 1.1049 -0.724916)
			(end 1.1049 0.724916)
			(stroke
				(width 0.1)
				(type default)
			)
			(layer "B.Fab")
		)
		(pad "1" smd rect
			(at 0.889 0 270)
			(size 1.016 1.27)
			(layers "B.Cu" "B.Mask" "B.Paste")
			(net "PVDDIO_P0")
		)
		(pad "2" smd rect
			(at -0.889 0 270)
			(size 1.016 1.27)
			(layers "B.Cu" "B.Mask" "B.Paste")
			(net "GND")
		)
	)
	(footprint ""
		(layer "B.Cu")
		(at 105.577386 -269.307564)
		(property "Reference" "C2351"
			(at 0 0 0)
			(layer "B.SilkS")
			(hide yes)
			(effects
				(font
					(size 1.27 1.27)
				)
				(justify mirror)
			)
		)
		(property "Value" ""
			(at 0 0 0)
			(layer "B.Fab")
			(effects
				(font
					(size 1.27 1.27)
				)
				(justify mirror)
			)
		)
		(duplicate_pad_numbers_are_jumpers no)
		(fp_line
			(start -0.7874 -0.4064)
			(end -0.7874 0.4064)
			(stroke
				(width 0.1524)
				(type default)
			)
			(layer "B.SilkS")
		)
		(fp_line
			(start -0.7874 0.4064)
			(end 0.7874 0.4064)
			(stroke
				(width 0.1524)
				(type default)
			)
			(layer "B.SilkS")
		)
		(fp_line
			(start 0.7874 -0.4064)
			(end -0.7874 -0.4064)
			(stroke
				(width 0.1524)
				(type default)
			)
			(layer "B.SilkS")
		)
		(fp_line
			(start 0.7874 0.4064)
			(end 0.7874 -0.4064)
			(stroke
				(width 0.1524)
				(type default)
			)
			(layer "B.SilkS")
		)
		(fp_line
			(start -0.67945 -0.3048)
			(end -0.67945 0.3048)
			(stroke
				(width 0.1)
				(type default)
			)
			(layer "B.Fab")
		)
		(fp_line
			(start -0.67945 0.3048)
			(end -0.120396 0.3048)
			(stroke
				(width 0.1)
				(type default)
			)
			(layer "B.Fab")
		)
		(fp_line
			(start -0.12065 -0.3048)
			(end -0.67945 -0.3048)
			(stroke
				(width 0.1)
				(type default)
			)
			(layer "B.Fab")
		)
		(fp_line
			(start -0.12065 -0.2794)
			(end -0.12065 -0.3048)
			(stroke
				(width 0.1)
				(type default)
			)
			(layer "B.Fab")
		)
		(fp_line
			(start -0.120396 0.2794)
			(end 0.12065 0.2794)
			(stroke
				(width 0.1)
				(type default)
			)
			(layer "B.Fab")
		)
		(fp_line
			(start -0.120396 0.3048)
			(end -0.120396 0.2794)
			(stroke
				(width 0.1)
				(type default)
			)
			(layer "B.Fab")
		)
		(fp_line
			(start 0.12065 -0.305054)
			(end 0.12065 -0.2794)
			(stroke
				(width 0.1)
				(type default)
			)
			(layer "B.Fab")
		)
		(fp_line
			(start 0.12065 -0.2794)
			(end -0.12065 -0.2794)
			(stroke
				(width 0.1)
				(type default)
			)
			(layer "B.Fab")
		)
		(fp_line
			(start 0.12065 0.2794)
			(end 0.12065 0.3048)
			(stroke
				(width 0.1)
				(type default)
			)
			(layer "B.Fab")
		)
		(fp_line
			(start 0.12065 0.3048)
			(end 0.67945 0.3048)
			(stroke
				(width 0.1)
				(type default)
			)
			(layer "B.Fab")
		)
		(fp_line
			(start 0.67945 -0.305054)
			(end 0.12065 -0.305054)
			(stroke
				(width 0.1)
				(type default)
			)
			(layer "B.Fab")
		)
		(fp_line
			(start 0.67945 0.3048)
			(end 0.67945 -0.305054)
			(stroke
				(width 0.1)
				(type default)
			)
			(layer "B.Fab")
		)
		(pad "1" smd circle
			(at 0.40005 0 180)
			(size 0 0)
			(layers "B.Cu" "B.Mask" "B.Paste")
			(net "PVDDCR_CPU1_P1")
		)
		(pad "2" smd circle
			(at -0.40005 0 180)
			(size 0 0)
			(layers "B.Cu" "B.Mask" "B.Paste")
			(net "GND")
		)
	)
)
